#ISCELL
  mstr_symbols cad_note *
  *
#ISCELL
  mstr_symbols design_note *
  *
#ISCELL
  mstr_symbols intel_corp_bpage *
  *
#CELL
  mstr_digital pca9517 *
  page163_i1
#CELL
  dev_discrete cap_a *
  page163_i10
#ISCELL
  mstr_symbols gnd *
  page163_i11
#CELL
  dev_discrete cap_a *
  page163_i12
#ISCELL
  mstr_symbols gnd *
  page163_i13
#CELL
  mstr_discrete res *
  page163_i15
#CELL
  mstr_discrete res *
  page163_i16
#ISCELL
  mstr_standard offpage *
  page163_i18
#ISCELL
  mstr_standard offpage *
  page163_i19
#CELL
  mstr_discrete res *
  page163_i2
#CELL
  mstr_discrete res *
  page163_i20
#CELL
  mstr_discrete res *
  page163_i21
#ISCELL
  mstr_standard offpage *
  page163_i22
#ISCELL
  mstr_standard offpage *
  page163_i23
#CELL
  mstr_discrete res *
  page163_i24
#CELL
  mstr_discrete res *
  page163_i25
#ISCELL
  mstr_symbols p3v3_stby *
  page163_i26
#ISCELL
  mstr_symbols p3v3_stby *
  page163_i27
#CELL
  mstr_discrete res *
  page163_i3
#ISCELL
  mstr_standard offpage *
  page163_i4
#ISCELL
  mstr_standard offpage *
  page163_i5
#CELL
  mstr_discrete res *
  page163_i6
#CELL
  mstr_discrete res *
  page163_i7
#ISCELL
  mstr_symbols pvccio_cpu1 *
  page163_i8
#ISCELL
  mstr_symbols pvccio_cpu1 *
  page163_i9
